# SCM (Grand Teton) — schematic netlist excerpt (pin names and nets, part order shuffled) for the footprints in the layout excerpt that follows; sources: Cadence DE-HDL packaged netlist, KiCad conversion of 12092022_DA0F0TMDCD0_F0T_Management_Board_D_brd_V3_OCP.brd

R643  Q_RES  33.2 1% CHIP  pkg 0402LF  page 13 : A = PWRGD_DSW_PWROK ; B = PWRGD_DSW_PWROK_R1
PC212  Q_CAP  0.1UF 25V 10% X7R  pkg 0402  page 51 : A = P5V_AUX ; B = GND

(kicad_pcb
	(version 20260206)
	(generator "pcbnew")
	(generator_version "10.0")
	(general
		(thickness 1.6)
		(legacy_teardrops no)
	)
	(paper "A4")
	(title_block
		(title "12092022_DA0F0TMDCD0_F0T_Management_Board_D_brd_V3_OCP.brd")
		(comment 1 "Grand Teton / footprints 442-443 of 1440")
	)
	(layers
		(0 "F.Cu" signal "TOP")
		(4 "In1.Cu" signal "GND")
		(6 "In2.Cu" signal "IN1")
		(8 "In3.Cu" signal "GND1")
		(10 "In4.Cu" signal "IN2")
		(12 "In5.Cu" signal "VCC")
		(14 "In6.Cu" signal "VCC1")
		(16 "In7.Cu" signal "IN3")
		(18 "In8.Cu" signal "GND2")
		(20 "In9.Cu" signal "IN4")
		(22 "In10.Cu" signal "GND3")
		(2 "B.Cu" signal "BOTTOM")
		(9 "F.Adhes" user "F.Adhesive")
		(11 "B.Adhes" user "B.Adhesive")
		(13 "F.Paste" user "Package Geometry/Pastemask Top")
		(15 "B.Paste" user "Package Geometry/Pastemask Bottom")
		(5 "F.SilkS" user "Ref Des/Silkscreen Top")
		(7 "B.SilkS" user "Ref Des/Silkscreen Bottom")
		(1 "F.Mask" user "Board Geometry/Soldermask Top")
		(3 "B.Mask" user "Board Geometry/Soldermask Bottom")
		(17 "Dwgs.User" user "User.Drawings")
		(19 "Cmts.User" user "User.Comments")
		(21 "Eco1.User" user "User.Eco1")
		(23 "Eco2.User" user "User.Eco2")
		(25 "Edge.Cuts" user "Board Geometry/Outline")
		(27 "Margin" user)
		(31 "F.CrtYd" user "Package Geometry/Place Bound Top")
		(29 "B.CrtYd" user "Package Geometry/Place Bound Bottom")
		(35 "F.Fab" user "Ref Des/Assembly Top")
		(33 "B.Fab" user "Ref Des/Assembly Bottom")
	)
	(footprint ""
		(layer "F.Cu")
		(at 13.22197 -31.800292 -90)
		(property "Reference" "PC212"
			(at 0 0 270)
			(layer "F.SilkS")
			(hide yes)
			(effects
				(font
					(size 1.27 1.27)
				)
			)
		)
		(property "Value" ""
			(at 0 0 270)
			(layer "F.Fab")
			(effects
				(font
					(size 1.27 1.27)
				)
			)
		)
		(duplicate_pad_numbers_are_jumpers no)
		(fp_line
			(start -0.7874 0.4064)
			(end -0.7874 -0.4064)
			(stroke
				(width 0.1524)
				(type default)
			)
			(layer "F.SilkS")
		)
		(fp_line
			(start 0.7874 0.4064)
			(end -0.7874 0.4064)
			(stroke
				(width 0.1524)
				(type default)
			)
			(layer "F.SilkS")
		)
		(fp_line
			(start -0.7874 -0.4064)
			(end 0.7874 -0.4064)
			(stroke
				(width 0.1524)
				(type default)
			)
			(layer "F.SilkS")
		)
		(fp_line
			(start 0.7874 -0.4064)
			(end 0.7874 0.4064)
			(stroke
				(width 0.1524)
				(type default)
			)
			(layer "F.SilkS")
		)
		(fp_line
			(start -0.67945 0.3048)
			(end -0.67945 -0.305054)
			(stroke
				(width 0.1)
				(type default)
			)
			(layer "F.Fab")
		)
		(fp_line
			(start -0.12065 0.3048)
			(end -0.67945 0.3048)
			(stroke
				(width 0.1)
				(type default)
			)
			(layer "F.Fab")
		)
		(fp_line
			(start 0.120396 0.3048)
			(end 0.120396 0.2794)
			(stroke
				(width 0.1)
				(type default)
			)
			(layer "F.Fab")
		)
		(fp_line
			(start 0.67945 0.3048)
			(end 0.120396 0.3048)
			(stroke
				(width 0.1)
				(type default)
			)
			(layer "F.Fab")
		)
		(fp_line
			(start -0.12065 0.2794)
			(end -0.12065 0.3048)
			(stroke
				(width 0.1)
				(type default)
			)
			(layer "F.Fab")
		)
		(fp_line
			(start 0.120396 0.2794)
			(end -0.12065 0.2794)
			(stroke
				(width 0.1)
				(type default)
			)
			(layer "F.Fab")
		)
		(fp_line
			(start -0.12065 -0.2794)
			(end 0.12065 -0.2794)
			(stroke
				(width 0.1)
				(type default)
			)
			(layer "F.Fab")
		)
		(fp_line
			(start 0.12065 -0.2794)
			(end 0.12065 -0.3048)
			(stroke
				(width 0.1)
				(type default)
			)
			(layer "F.Fab")
		)
		(fp_line
			(start 0.12065 -0.3048)
			(end 0.67945 -0.3048)
			(stroke
				(width 0.1)
				(type default)
			)
			(layer "F.Fab")
		)
		(fp_line
			(start 0.67945 -0.3048)
			(end 0.67945 0.3048)
			(stroke
				(width 0.1)
				(type default)
			)
			(layer "F.Fab")
		)
		(fp_line
			(start -0.67945 -0.305054)
			(end -0.12065 -0.305054)
			(stroke
				(width 0.1)
				(type default)
			)
			(layer "F.Fab")
		)
		(fp_line
			(start -0.12065 -0.305054)
			(end -0.12065 -0.2794)
			(stroke
				(width 0.1)
				(type default)
			)
			(layer "F.Fab")
		)
		(pad "1" smd circle
			(at -0.40005 0 270)
			(size 0 0)
			(layers "F.Cu" "F.Mask" "F.Paste")
			(net "P5V_AUX")
		)
		(pad "2" smd circle
			(at 0.40005 0 270)
			(size 0 0)
			(layers "F.Cu" "F.Mask" "F.Paste")
			(net "GND")
		)
	)
	(footprint ""
		(layer "F.Cu")
		(at 65.056512 -63.926466 -90)
		(property "Reference" "R643"
			(at 0 0 270)
			(layer "F.SilkS")
			(hide yes)
			(effects
				(font
					(size 1.27 1.27)
				)
			)
		)
		(property "Value" ""
			(at 0 0 270)
			(layer "F.Fab")
			(effects
				(font
					(size 1.27 1.27)
				)
			)
		)
		(duplicate_pad_numbers_are_jumpers no)
		(fp_line
			(start -0.7874 0.4064)
			(end -0.7874 -0.4064)
			(stroke
				(width 0.1524)
				(type default)
			)
			(layer "F.SilkS")
		)
		(fp_line
			(start 0.7874 0.4064)
			(end -0.7874 0.4064)
			(stroke
				(width 0.1524)
				(type default)
			)
			(layer "F.SilkS")
		)
		(fp_line
			(start -0.7874 -0.4064)
			(end 0.7874 -0.4064)
			(stroke
				(width 0.1524)
				(type default)
			)
			(layer "F.SilkS")
		)
		(fp_line
			(start 0.7874 -0.4064)
			(end 0.7874 0.4064)
			(stroke
				(width 0.1524)
				(type default)
			)
			(layer "F.SilkS")
		)
		(fp_line
			(start -0.67945 0.3048)
			(end -0.67945 -0.305054)
			(stroke
				(width 0.1)
				(type default)
			)
			(layer "F.Fab")
		)
		(fp_line
			(start -0.12065 0.3048)
			(end -0.67945 0.3048)
			(stroke
				(width 0.1)
				(type default)
			)
			(layer "F.Fab")
		)
		(fp_line
			(start 0.120396 0.3048)
			(end 0.120396 0.2794)
			(stroke
				(width 0.1)
				(type default)
			)
			(layer "F.Fab")
		)
		(fp_line
			(start 0.67945 0.3048)
			(end 0.120396 0.3048)
			(stroke
				(width 0.1)
				(type default)
			)
			(layer "F.Fab")
		)
		(fp_line
			(start -0.12065 0.2794)
			(end -0.12065 0.3048)
			(stroke
				(width 0.1)
				(type default)
			)
			(layer "F.Fab")
		)
		(fp_line
			(start 0.120396 0.2794)
			(end -0.12065 0.2794)
			(stroke
				(width 0.1)
				(type default)
			)
			(layer "F.Fab")
		)
		(fp_line
			(start -0.12065 -0.2794)
			(end 0.12065 -0.2794)
			(stroke
				(width 0.1)
				(type default)
			)
			(layer "F.Fab")
		)
		(fp_line
			(start 0.12065 -0.2794)
			(end 0.12065 -0.3048)
			(stroke
				(width 0.1)
				(type default)
			)
			(layer "F.Fab")
		)
		(fp_line
			(start 0.12065 -0.3048)
			(end 0.67945 -0.3048)
			(stroke
				(width 0.1)
				(type default)
			)
			(layer "F.Fab")
		)
		(fp_line
			(start 0.67945 -0.3048)
			(end 0.67945 0.3048)
			(stroke
				(width 0.1)
				(type default)
			)
			(layer "F.Fab")
		)
		(fp_line
			(start -0.67945 -0.305054)
			(end -0.12065 -0.305054)
			(stroke
				(width 0.1)
				(type default)
			)
			(layer "F.Fab")
		)
		(fp_line
			(start -0.12065 -0.305054)
			(end -0.12065 -0.2794)
			(stroke
				(width 0.1)
				(type default)
			)
			(layer "F.Fab")
		)
		(pad "1" smd circle
			(at -0.40005 0 270)
			(size 0 0)
			(layers "F.Cu" "F.Mask" "F.Paste")
			(net "PWRGD_DSW_PWROK")
		)
		(pad "2" smd circle
			(at 0.40005 0 270)
			(size 0 0)
			(layers "F.Cu" "F.Mask" "F.Paste")
			(net "PWRGD_DSW_PWROK_R1")
		)
	)
)
